# T6G (Grand Teton) — schematic netlist excerpt (pin names and nets, part order shuffled) for the footprints in the layout excerpt that follows; sources: Cadence DE-HDL packaged netlist, KiCad conversion of 04192023_DAF0TMB3IC0_F0TG_MB_C_brd_V02_OCP.brd

U270  LM75BD  IC  pkg SO8_1-27_4-9X3-9  page 235
  SDA  = SMB_LM75_0_3V3AUX_SDA_R1
  SCL  = SMB_LM75_0_3V3AUX_SCL_R1
  OS  = FM_G751_0_ALERT_N
  GND  = GND
  A2  = U270_0_ADD2
  A1  = U270_0_ADD1
  A0  = U270_0_ADD0
  VCC  = P3V3_AUX

(kicad_pcb
	(version 20260206)
	(generator "pcbnew")
	(generator_version "10.0")
	(general
		(thickness 1.6)
		(legacy_teardrops no)
	)
	(paper "A4")
	(title_block
		(title "04192023_DAF0TMB3IC0_F0TG_MB_C_brd_V02_OCP.brd")
		(comment 1 "Grand Teton / footprints 3075-3075 of 8354")
	)
	(layers
		(0 "F.Cu" signal "TOP")
		(4 "In1.Cu" signal "GND")
		(6 "In2.Cu" signal "IN1")
		(8 "In3.Cu" signal "GND1")
		(10 "In4.Cu" signal "IN2")
		(12 "In5.Cu" signal "GND2")
		(14 "In6.Cu" signal "IN3")
		(16 "In7.Cu" signal "GND3")
		(18 "In8.Cu" signal "VCC")
		(20 "In9.Cu" signal "VCC1")
		(22 "In10.Cu" signal "GND4")
		(24 "In11.Cu" signal "IN4")
		(26 "In12.Cu" signal "GND5")
		(28 "In13.Cu" signal "IN5")
		(30 "In14.Cu" signal "GND6")
		(32 "In15.Cu" signal "IN6")
		(34 "In16.Cu" signal "GND7")
		(2 "B.Cu" signal "BOTTOM")
		(9 "F.Adhes" user "F.Adhesive")
		(11 "B.Adhes" user "B.Adhesive")
		(13 "F.Paste" user "Package Geometry/Pastemask Top")
		(15 "B.Paste" user "Package Geometry/Pastemask Bottom")
		(5 "F.SilkS" user "Ref Des/Silkscreen Top")
		(7 "B.SilkS" user "Ref Des/Silkscreen Bottom")
		(1 "F.Mask" user "Board Geometry/Soldermask Top")
		(3 "B.Mask" user "Board Geometry/Soldermask Bottom")
		(17 "Dwgs.User" user "User.Drawings")
		(19 "Cmts.User" user "User.Comments")
		(21 "Eco1.User" user "User.Eco1")
		(23 "Eco2.User" user "User.Eco2")
		(25 "Edge.Cuts" user "Board Geometry/Outline")
		(27 "Margin" user)
		(31 "F.CrtYd" user "Package Geometry/Place Bound Top")
		(29 "B.CrtYd" user "Package Geometry/Place Bound Bottom")
		(35 "F.Fab" user "Ref Des/Assembly Top")
		(33 "B.Fab" user "Ref Des/Assembly Bottom")
	)
	(footprint ""
		(layer "F.Cu")
		(at 367.812066 -419.29558 90)
		(property "Reference" "U270"
			(at -0.13208 -2.975864 90)
			(unlocked yes)
			(layer "F.SilkS")
			(effects
				(font
					(size 0.7874 0.5842)
					(thickness 0.1524)
				)
				(justify left)
			)
		)
		(property "Value" ""
			(at 0 0 90)
			(layer "F.Fab")
			(effects
				(font
					(size 1.27 1.27)
				)
			)
		)
		(duplicate_pad_numbers_are_jumpers no)
		(fp_line
			(start 3.447796 -2.500122)
			(end 1.484122 -2.500122)
			(stroke
				(width 0.1524)
				(type default)
			)
			(layer "F.SilkS")
		)
		(fp_line
			(start 1.484122 -2.500122)
			(end 0 -1.016)
			(stroke
				(width 0.1524)
				(type default)
			)
			(layer "F.SilkS")
		)
		(fp_line
			(start -1.484122 -2.500122)
			(end -3.447796 -2.500122)
			(stroke
				(width 0.1524)
				(type default)
			)
			(layer "F.SilkS")
		)
		(fp_line
			(start -3.447796 -2.500122)
			(end -3.447796 2.500122)
			(stroke
				(width 0.1524)
				(type default)
			)
			(layer "F.SilkS")
		)
		(fp_line
			(start 0 -1.016)
			(end -1.484122 -2.500122)
			(stroke
				(width 0.1524)
				(type default)
			)
			(layer "F.SilkS")
		)
		(fp_line
			(start 3.447796 2.500122)
			(end 3.447796 -2.500122)
			(stroke
				(width 0.1524)
				(type default)
			)
			(layer "F.SilkS")
		)
		(fp_line
			(start -3.447796 2.500122)
			(end 3.447796 2.500122)
			(stroke
				(width 0.1524)
				(type default)
			)
			(layer "F.SilkS")
		)
		(fp_poly
			(pts
				(xy -1.063244 -3.198876) (xy -0.561848 -2.775966) (xy -1.235456 -2.485898)
			)
			(stroke
				(width 0)
				(type default)
			)
			(fill yes)
			(layer "F.SilkS")
		)
		(fp_line
			(start 1.999996 -2.500122)
			(end -1.999996 -2.500122)
			(stroke
				(width 0.1)
				(type default)
			)
			(layer "F.Fab")
		)
		(fp_line
			(start -1.999996 -2.500122)
			(end -1.999996 2.500122)
			(stroke
				(width 0.1)
				(type default)
			)
			(layer "F.Fab")
		)
		(fp_line
			(start 1.999996 2.500122)
			(end 1.999996 -2.500122)
			(stroke
				(width 0.1)
				(type default)
			)
			(layer "F.Fab")
		)
		(fp_line
			(start -1.999996 2.500122)
			(end 1.999996 2.500122)
			(stroke
				(width 0.1)
				(type default)
			)
			(layer "F.Fab")
		)
		(fp_poly
			(pts
				(xy -4.5974 -2.413) (xy -4.5974 -1.397) (xy -3.5814 -1.905)
			)
			(stroke
				(width 0)
				(type default)
			)
			(fill yes)
			(layer "F.Fab")
		)
		(pad "1" smd rect
			(at -2.649982 -1.905)
			(size 0.6096 1.3208)
			(layers "F.Cu" "F.Mask" "F.Paste")
			(net "SMB_LM75_0_3V3AUX_SDA_R1")
		)
		(pad "2" smd rect
			(at -2.649982 -0.635)
			(size 0.6096 1.3208)
			(layers "F.Cu" "F.Mask" "F.Paste")
			(net "SMB_LM75_0_3V3AUX_SCL_R1")
		)
		(pad "3" smd rect
			(at -2.649982 0.635)
			(size 0.6096 1.3208)
			(layers "F.Cu" "F.Mask" "F.Paste")
			(net "FM_G751_0_ALERT_N")
		)
		(pad "4" smd rect
			(at -2.649982 1.905)
			(size 0.6096 1.3208)
			(layers "F.Cu" "F.Mask" "F.Paste")
			(net "GND")
		)
		(pad "5" smd rect
			(at 2.649982 1.905)
			(size 0.6096 1.3208)
			(layers "F.Cu" "F.Mask" "F.Paste")
			(net "U270_0_ADD2")
		)
		(pad "6" smd rect
			(at 2.649982 0.635)
			(size 0.6096 1.3208)
			(layers "F.Cu" "F.Mask" "F.Paste")
			(net "U270_0_ADD1")
		)
		(pad "7" smd rect
			(at 2.649982 -0.635)
			(size 0.6096 1.3208)
			(layers "F.Cu" "F.Mask" "F.Paste")
			(net "U270_0_ADD0")
		)
		(pad "8" smd rect
			(at 2.649982 -1.905)
			(size 0.6096 1.3208)
			(layers "F.Cu" "F.Mask" "F.Paste")
			(net "P3V3_AUX")
		)
	)
)
